(kicad_pcb
	(version 20260206)
	(generator "pcbnew")
	(generator_version "10.0")
	(general
		(thickness 1.6)
		(legacy_teardrops no)
	)
	(paper "A4")
	(title_block
		(title "01162023_DA0F0TEBIF0_F0T_Expander_BD_F_brd_V02_OCP.brd")
		(comment 1 "Grand Teton / footprints 471-477 of 9728")
	)
	(layers
		(0 "F.Cu" signal "TOP")
		(4 "In1.Cu" signal "GND")
		(6 "In2.Cu" signal "VCC")
		(8 "In3.Cu" signal "VCC1")
		(10 "In4.Cu" signal "GND1")
		(12 "In5.Cu" signal "IN1")
		(14 "In6.Cu" signal "GND2")
		(16 "In7.Cu" signal "IN2")
		(18 "In8.Cu" signal "GND3")
		(20 "In9.Cu" signal "IN3")
		(22 "In10.Cu" signal "GND4")
		(24 "In11.Cu" signal "IN4")
		(26 "In12.Cu" signal "GND5")
		(28 "In13.Cu" signal "IN5")
		(30 "In14.Cu" signal "GND6")
		(32 "In15.Cu" signal "IN6")
		(34 "In16.Cu" signal "GND7")
		(2 "B.Cu" signal "BOTTOM")
		(9 "F.Adhes" user "F.Adhesive")
		(11 "B.Adhes" user "B.Adhesive")
		(13 "F.Paste" user "Package Geometry/Pastemask Top")
		(15 "B.Paste" user "Package Geometry/Pastemask Bottom")
		(5 "F.SilkS" user "Ref Des/Silkscreen Top")
		(7 "B.SilkS" user "Ref Des/Silkscreen Bottom")
		(1 "F.Mask" user "Board Geometry/Soldermask Top")
		(3 "B.Mask" user "Board Geometry/Soldermask Bottom")
		(17 "Dwgs.User" user "User.Drawings")
		(19 "Cmts.User" user "User.Comments")
		(21 "Eco1.User" user "User.Eco1")
		(23 "Eco2.User" user "User.Eco2")
		(25 "Edge.Cuts" user "Board Geometry/Outline")
		(27 "Margin" user)
		(31 "F.CrtYd" user "Package Geometry/Place Bound Top")
		(29 "B.CrtYd" user "Package Geometry/Place Bound Bottom")
		(35 "F.Fab" user "Ref Des/Assembly Top")
		(33 "B.Fab" user "Ref Des/Assembly Bottom")
	)
	(footprint ""
		(layer "F.Cu")
		(at 123.614434 -303.698402 90)
		(property "Reference" "PC119"
			(at 0 0 90)
			(layer "F.SilkS")
			(hide yes)
			(effects
				(font
					(size 1.27 1.27)
				)
			)
		)
		(property "Value" ""
			(at 0 0 90)
			(layer "F.Fab")
			(effects
				(font
					(size 1.27 1.27)
				)
			)
		)
		(duplicate_pad_numbers_are_jumpers no)
		(fp_line
			(start -4.53898 -2.150618)
			(end -4.539742 2.152142)
			(stroke
				(width 0.1524)
				(type default)
			)
			(layer "F.SilkS")
		)
		(fp_line
			(start -4.69138 -2.150618)
			(end -4.692396 2.161032)
			(stroke
				(width 0.1524)
				(type default)
			)
			(layer "F.SilkS")
		)
		(fp_line
			(start -4.84378 -2.150618)
			(end -4.53898 -2.150618)
			(stroke
				(width 0.1524)
				(type default)
			)
			(layer "F.SilkS")
		)
		(fp_line
			(start -4.84378 -2.150618)
			(end -4.842256 2.163064)
			(stroke
				(width 0.1524)
				(type default)
			)
			(layer "F.SilkS")
		)
		(fp_line
			(start 4.53898 -2.15011)
			(end 4.53898 2.15011)
			(stroke
				(width 0.1524)
				(type default)
			)
			(layer "F.SilkS")
		)
		(fp_line
			(start -4.53898 -2.15011)
			(end 4.53898 -2.15011)
			(stroke
				(width 0.1524)
				(type default)
			)
			(layer "F.SilkS")
		)
		(fp_line
			(start 4.53898 2.15011)
			(end -4.53898 2.15011)
			(stroke
				(width 0.1524)
				(type default)
			)
			(layer "F.SilkS")
		)
		(fp_line
			(start -4.53898 2.15011)
			(end -4.53898 -2.15011)
			(stroke
				(width 0.1524)
				(type default)
			)
			(layer "F.SilkS")
		)
		(fp_line
			(start -4.83108 2.150364)
			(end -4.447794 2.149348)
			(stroke
				(width 0.1524)
				(type default)
			)
			(layer "F.SilkS")
		)
		(fp_line
			(start 3.64998 -2.15011)
			(end 3.64998 2.15011)
			(stroke
				(width 0.1)
				(type default)
			)
			(layer "F.Fab")
		)
		(fp_line
			(start -3.64998 -2.15011)
			(end 3.64998 -2.15011)
			(stroke
				(width 0.1)
				(type default)
			)
			(layer "F.Fab")
		)
		(fp_line
			(start 3.64998 2.15011)
			(end -3.64998 2.15011)
			(stroke
				(width 0.1)
				(type default)
			)
			(layer "F.Fab")
		)
		(fp_line
			(start -3.64998 2.15011)
			(end -3.64998 -2.15011)
			(stroke
				(width 0.1)
				(type default)
			)
			(layer "F.Fab")
		)
		(fp_text user "+"
			(at -4.575048 -3.013202 90)
			(unlocked yes)
			(layer "F.SilkS")
			(effects
				(font
					(size 1.905 1.4224)
					(thickness 0.1524)
				)
				(justify left)
			)
		)
		(fp_text user "-"
			(at 3.295396 -2.940304 90)
			(unlocked yes)
			(layer "F.SilkS")
			(effects
				(font
					(size 1.905 1.4224)
					(thickness 0.1524)
				)
				(justify left)
			)
		)
		(fp_text user "+"
			(at -6.214872 -0.337058 90)
			(unlocked yes)
			(layer "F.Fab")
			(effects
				(font
					(size 1.905 1.4224)
					(thickness 0.1524)
				)
				(justify left)
			)
		)
		(fp_text user "-"
			(at 4.313174 -0.094488 90)
			(unlocked yes)
			(layer "F.Fab")
			(effects
				(font
					(size 1.905 1.4224)
					(thickness 0.1524)
				)
				(justify left)
			)
		)
		(pad "1" smd rect
			(at -3.199892 0 90)
			(size 2.413 2.8194)
			(layers "F.Cu" "F.Mask" "F.Paste")
			(net "P0V8_PEX1")
		)
		(pad "2" smd rect
			(at 3.199892 0 90)
			(size 2.413 2.8194)
			(layers "F.Cu" "F.Mask" "F.Paste")
			(net "GND")
		)
	)
	(footprint ""
		(layer "F.Cu")
		(at 199.651366 -411.279594 -90)
		(property "Reference" "U444"
			(at 0.461772 -2.178558 90)
			(unlocked yes)
			(layer "F.SilkS")
			(effects
				(font
					(size 0.7874 0.5842)
					(thickness 0.1524)
				)
				(justify left)
			)
		)
		(property "Value" ""
			(at 0 0 270)
			(layer "F.Fab")
			(effects
				(font
					(size 1.27 1.27)
				)
			)
		)
		(duplicate_pad_numbers_are_jumpers no)
		(fp_line
			(start -1.868424 1.519936)
			(end 1.868424 1.519936)
			(stroke
				(width 0.1524)
				(type default)
			)
			(layer "F.SilkS")
		)
		(fp_line
			(start 1.868424 1.519936)
			(end 1.868424 -1.519936)
			(stroke
				(width 0.1524)
				(type default)
			)
			(layer "F.SilkS")
		)
		(fp_line
			(start -1.868424 -1.519936)
			(end -1.868424 1.519936)
			(stroke
				(width 0.1524)
				(type default)
			)
			(layer "F.SilkS")
		)
		(fp_line
			(start 1.868424 -1.519936)
			(end -1.868424 -1.519936)
			(stroke
				(width 0.1524)
				(type default)
			)
			(layer "F.SilkS")
		)
		(fp_line
			(start -0.700024 1.519936)
			(end 0.700024 1.519936)
			(stroke
				(width 0.1)
				(type default)
			)
			(layer "F.Fab")
		)
		(fp_line
			(start 0.700024 1.519936)
			(end 0.700024 -1.519936)
			(stroke
				(width 0.1)
				(type default)
			)
			(layer "F.Fab")
		)
		(fp_line
			(start -0.700024 -1.519936)
			(end -0.700024 1.519936)
			(stroke
				(width 0.1)
				(type default)
			)
			(layer "F.Fab")
		)
		(fp_line
			(start 0.700024 -1.519936)
			(end -0.700024 -1.519936)
			(stroke
				(width 0.1)
				(type default)
			)
			(layer "F.Fab")
		)
		(pad "1" smd rect
			(at -1.18491 -0.94996 180)
			(size 0.6096 1.0668)
			(layers "F.Cu" "F.Mask" "F.Paste")
			(net "UV_P2V5_COMP")
		)
		(pad "2" smd rect
			(at -1.18491 0.94996 180)
			(size 0.6096 1.0668)
			(layers "F.Cu" "F.Mask" "F.Paste")
			(net "GND")
		)
		(pad "3" smd rect
			(at 1.18491 0 180)
			(size 0.6096 1.0668)
			(layers "F.Cu" "F.Mask" "F.Paste")
			(net "Net_9326")
		)
	)
	(footprint ""
		(layer "F.Cu")
		(at 186.372754 -415.15919 180)
		(property "Reference" "R6778"
			(at 0 0 180)
			(layer "F.SilkS")
			(hide yes)
			(effects
				(font
					(size 1.27 1.27)
				)
			)
		)
		(property "Value" ""
			(at 0 0 180)
			(layer "F.Fab")
			(effects
				(font
					(size 1.27 1.27)
				)
			)
		)
		(duplicate_pad_numbers_are_jumpers no)
		(fp_line
			(start 0.7874 0.4064)
			(end -0.7874 0.4064)
			(stroke
				(width 0.1524)
				(type default)
			)
			(layer "F.SilkS")
		)
		(fp_line
			(start 0.7874 -0.4064)
			(end 0.7874 0.4064)
			(stroke
				(width 0.1524)
				(type default)
			)
			(layer "F.SilkS")
		)
		(fp_line
			(start -0.7874 0.4064)
			(end -0.7874 -0.4064)
			(stroke
				(width 0.1524)
				(type default)
			)
			(layer "F.SilkS")
		)
		(fp_line
			(start -0.7874 -0.4064)
			(end 0.7874 -0.4064)
			(stroke
				(width 0.1524)
				(type default)
			)
			(layer "F.SilkS")
		)
		(fp_line
			(start 0.67945 0.3048)
			(end 0.120396 0.3048)
			(stroke
				(width 0.1)
				(type default)
			)
			(layer "F.Fab")
		)
		(fp_line
			(start 0.67945 -0.3048)
			(end 0.67945 0.3048)
			(stroke
				(width 0.1)
				(type default)
			)
			(layer "F.Fab")
		)
		(fp_line
			(start 0.12065 -0.2794)
			(end 0.12065 -0.3048)
			(stroke
				(width 0.1)
				(type default)
			)
			(layer "F.Fab")
		)
		(fp_line
			(start 0.12065 -0.3048)
			(end 0.67945 -0.3048)
			(stroke
				(width 0.1)
				(type default)
			)
			(layer "F.Fab")
		)
		(fp_line
			(start 0.120396 0.3048)
			(end 0.120396 0.2794)
			(stroke
				(width 0.1)
				(type default)
			)
			(layer "F.Fab")
		)
		(fp_line
			(start 0.120396 0.2794)
			(end -0.12065 0.2794)
			(stroke
				(width 0.1)
				(type default)
			)
			(layer "F.Fab")
		)
		(fp_line
			(start -0.12065 0.3048)
			(end -0.67945 0.3048)
			(stroke
				(width 0.1)
				(type default)
			)
			(layer "F.Fab")
		)
		(fp_line
			(start -0.12065 0.2794)
			(end -0.12065 0.3048)
			(stroke
				(width 0.1)
				(type default)
			)
			(layer "F.Fab")
		)
		(fp_line
			(start -0.12065 -0.2794)
			(end 0.12065 -0.2794)
			(stroke
				(width 0.1)
				(type default)
			)
			(layer "F.Fab")
		)
		(fp_line
			(start -0.12065 -0.305054)
			(end -0.12065 -0.2794)
			(stroke
				(width 0.1)
				(type default)
			)
			(layer "F.Fab")
		)
		(fp_line
			(start -0.67945 0.3048)
			(end -0.67945 -0.305054)
			(stroke
				(width 0.1)
				(type default)
			)
			(layer "F.Fab")
		)
		(fp_line
			(start -0.67945 -0.305054)
			(end -0.12065 -0.305054)
			(stroke
				(width 0.1)
				(type default)
			)
			(layer "F.Fab")
		)
		(pad "1" smd circle
			(at -0.40005 0 180)
			(size 0 0)
			(layers "F.Cu" "F.Mask" "F.Paste")
			(net "P3V3_AUX")
		)
		(pad "2" smd circle
			(at 0.40005 0 180)
			(size 0 0)
			(layers "F.Cu" "F.Mask" "F.Paste")
			(net "HSC_UV_R_N")
		)
	)
	(footprint ""
		(layer "F.Cu")
		(at 17.792446 -29.139642 180)
		(property "Reference" "C71"
			(at 0 0 180)
			(layer "F.SilkS")
			(hide yes)
			(effects
				(font
					(size 1.27 1.27)
				)
			)
		)
		(property "Value" ""
			(at 0 0 180)
			(layer "F.Fab")
			(effects
				(font
					(size 1.27 1.27)
				)
			)
		)
		(duplicate_pad_numbers_are_jumpers no)
		(fp_line
			(start 0.299974 0.150114)
			(end -0.299974 0.150114)
			(stroke
				(width 0.1)
				(type default)
			)
			(layer "F.Fab")
		)
		(fp_line
			(start 0.299974 -0.150114)
			(end 0.299974 0.150114)
			(stroke
				(width 0.1)
				(type default)
			)
			(layer "F.Fab")
		)
		(fp_line
			(start -0.299974 0.150114)
			(end -0.299974 -0.150114)
			(stroke
				(width 0.1)
				(type default)
			)
			(layer "F.Fab")
		)
		(fp_line
			(start -0.299974 -0.150114)
			(end 0.299974 -0.150114)
			(stroke
				(width 0.1)
				(type default)
			)
			(layer "F.Fab")
		)
		(pad "1" smd rect
			(at -0.2667 0 180)
			(size 0.3048 0.381)
			(layers "F.Cu" "F.Mask" "F.Paste")
			(net "P5E_PEX0_STN2_TX_DP<44>")
		)
		(pad "2" smd rect
			(at 0.2667 0 180)
			(size 0.3048 0.381)
			(layers "F.Cu" "F.Mask" "F.Paste")
			(net "P5E_PEX0_STN2_TX_C_DP<44>")
		)
	)
	(footprint ""
		(layer "F.Cu")
		(at 350.795336 -35.48253)
		(property "Reference" "U395"
			(at -2.509266 1.24333 90)
			(unlocked yes)
			(layer "F.SilkS")
			(effects
				(font
					(size 0.7874 0.5842)
					(thickness 0.1524)
				)
				(justify left)
			)
		)
		(property "Value" ""
			(at 0 0 0)
			(layer "F.Fab")
			(effects
				(font
					(size 1.27 1.27)
				)
			)
		)
		(duplicate_pad_numbers_are_jumpers no)
		(fp_line
			(start -1.3462 -1.1938)
			(end -1.3462 1.1684)
			(stroke
				(width 0.1524)
				(type default)
			)
			(layer "F.SilkS")
		)
		(fp_line
			(start -1.3462 1.1938)
			(end 1.3462 1.1938)
			(stroke
				(width 0.1524)
				(type default)
			)
			(layer "F.SilkS")
		)
		(fp_line
			(start 1.3462 -1.1938)
			(end -1.3462 -1.1938)
			(stroke
				(width 0.1524)
				(type default)
			)
			(layer "F.SilkS")
		)
		(fp_line
			(start 1.3462 1.1938)
			(end 1.3462 -1.1938)
			(stroke
				(width 0.1524)
				(type default)
			)
			(layer "F.SilkS")
		)
		(fp_poly
			(pts
				(xy -1.447038 -0.760476) (xy -2.052066 -0.457962) (xy -2.052066 -1.06299)
			)
			(stroke
				(width 0)
				(type default)
			)
			(fill yes)
			(layer "F.SilkS")
		)
		(fp_line
			(start -0.674878 -1.124966)
			(end -0.674878 1.124966)
			(stroke
				(width 0.1)
				(type default)
			)
			(layer "F.Fab")
		)
		(fp_line
			(start -0.674878 1.124966)
			(end 0.674878 1.124966)
			(stroke
				(width 0.1)
				(type default)
			)
			(layer "F.Fab")
		)
		(fp_line
			(start 0.674878 -1.124966)
			(end -0.674878 -1.124966)
			(stroke
				(width 0.1)
				(type default)
			)
			(layer "F.Fab")
		)
		(fp_line
			(start 0.674878 1.124966)
			(end 0.674878 -1.124966)
			(stroke
				(width 0.1)
				(type default)
			)
			(layer "F.Fab")
		)
		(fp_poly
			(pts
				(xy -1.447038 -0.760476) (xy -2.052066 -0.457962) (xy -2.052066 -1.06299)
			)
			(stroke
				(width 0)
				(type default)
			)
			(fill yes)
			(layer "F.Fab")
		)
		(pad "1" smd rect
			(at -0.899922 -0.750062)
			(size 0.6096 0.6096)
			(layers "F.Cu" "F.Mask" "F.Paste")
			(net "PWRGD_P3V3_SSD12_R")
		)
		(pad "2" smd rect
			(at -0.899922 0 90)
			(size 0.4064 0.6096)
			(layers "F.Cu" "F.Mask" "F.Paste")
			(net "RST_SMB_SSD12_N")
		)
		(pad "3" smd rect
			(at -0.899922 0.750062)
			(size 0.6096 0.6096)
			(layers "F.Cu" "F.Mask" "F.Paste")
			(net "GND")
		)
		(pad "4" smd rect
			(at 0.899922 0.750062)
			(size 0.6096 0.6096)
			(layers "F.Cu" "F.Mask" "F.Paste")
			(net "RST_SMB_SSD12_ISO_N")
		)
		(pad "5" smd rect
			(at 0.899922 -0.750062)
			(size 0.6096 0.6096)
			(layers "F.Cu" "F.Mask" "F.Paste")
			(net "P3V3_AUX")
		)
	)
	(footprint ""
		(layer "F.Cu")
		(at 425.653962 -83.932268 90)
		(property "Reference" "C962"
			(at 0 0 90)
			(layer "F.SilkS")
			(hide yes)
			(effects
				(font
					(size 1.27 1.27)
				)
			)
		)
		(property "Value" ""
			(at 0 0 90)
			(layer "F.Fab")
			(effects
				(font
					(size 1.27 1.27)
				)
			)
		)
		(duplicate_pad_numbers_are_jumpers no)
		(fp_line
			(start 0.7874 -0.4064)
			(end 0.7874 0.4064)
			(stroke
				(width 0.1524)
				(type default)
			)
			(layer "F.SilkS")
		)
		(fp_line
			(start -0.7874 -0.4064)
			(end 0.7874 -0.4064)
			(stroke
				(width 0.1524)
				(type default)
			)
			(layer "F.SilkS")
		)
		(fp_line
			(start 0.7874 0.4064)
			(end -0.7874 0.4064)
			(stroke
				(width 0.1524)
				(type default)
			)
			(layer "F.SilkS")
		)
		(fp_line
			(start -0.7874 0.4064)
			(end -0.7874 -0.4064)
			(stroke
				(width 0.1524)
				(type default)
			)
			(layer "F.SilkS")
		)
		(fp_line
			(start -0.12065 -0.305054)
			(end -0.12065 -0.2794)
			(stroke
				(width 0.1)
				(type default)
			)
			(layer "F.Fab")
		)
		(fp_line
			(start -0.67945 -0.305054)
			(end -0.12065 -0.305054)
			(stroke
				(width 0.1)
				(type default)
			)
			(layer "F.Fab")
		)
		(fp_line
			(start 0.67945 -0.3048)
			(end 0.67945 0.3048)
			(stroke
				(width 0.1)
				(type default)
			)
			(layer "F.Fab")
		)
		(fp_line
			(start 0.12065 -0.3048)
			(end 0.67945 -0.3048)
			(stroke
				(width 0.1)
				(type default)
			)
			(layer "F.Fab")
		)
		(fp_line
			(start 0.12065 -0.2794)
			(end 0.12065 -0.3048)
			(stroke
				(width 0.1)
				(type default)
			)
			(layer "F.Fab")
		)
		(fp_line
			(start -0.12065 -0.2794)
			(end 0.12065 -0.2794)
			(stroke
				(width 0.1)
				(type default)
			)
			(layer "F.Fab")
		)
		(fp_line
			(start 0.120396 0.2794)
			(end -0.12065 0.2794)
			(stroke
				(width 0.1)
				(type default)
			)
			(layer "F.Fab")
		)
		(fp_line
			(start -0.12065 0.2794)
			(end -0.12065 0.3048)
			(stroke
				(width 0.1)
				(type default)
			)
			(layer "F.Fab")
		)
		(fp_line
			(start 0.67945 0.3048)
			(end 0.120396 0.3048)
			(stroke
				(width 0.1)
				(type default)
			)
			(layer "F.Fab")
		)
		(fp_line
			(start 0.120396 0.3048)
			(end 0.120396 0.2794)
			(stroke
				(width 0.1)
				(type default)
			)
			(layer "F.Fab")
		)
		(fp_line
			(start -0.12065 0.3048)
			(end -0.67945 0.3048)
			(stroke
				(width 0.1)
				(type default)
			)
			(layer "F.Fab")
		)
		(fp_line
			(start -0.67945 0.3048)
			(end -0.67945 -0.305054)
			(stroke
				(width 0.1)
				(type default)
			)
			(layer "F.Fab")
		)
		(pad "1" smd circle
			(at -0.40005 0 90)
			(size 0 0)
			(layers "F.Cu" "F.Mask" "F.Paste")
			(net "P3V3_AUX")
		)
		(pad "2" smd circle
			(at 0.40005 0 90)
			(size 0 0)
			(layers "F.Cu" "F.Mask" "F.Paste")
			(net "GND")
		)
	)
	(footprint ""
		(layer "F.Cu")
		(at 154.882596 -141.87297)
		(property "Reference" "R134"
			(at 0 0 0)
			(layer "F.SilkS")
			(hide yes)
			(effects
				(font
					(size 1.27 1.27)
				)
			)
		)
		(property "Value" ""
			(at 0 0 0)
			(layer "F.Fab")
			(effects
				(font
					(size 1.27 1.27)
				)
			)
		)
		(duplicate_pad_numbers_are_jumpers no)
		(fp_line
			(start -0.7874 -0.4064)
			(end 0.7874 -0.4064)
			(stroke
				(width 0.1524)
				(type default)
			)
			(layer "F.SilkS")
		)
		(fp_line
			(start -0.7874 0.4064)
			(end -0.7874 -0.4064)
			(stroke
				(width 0.1524)
				(type default)
			)
			(layer "F.SilkS")
		)
		(fp_line
			(start 0.7874 -0.4064)
			(end 0.7874 0.4064)
			(stroke
				(width 0.1524)
				(type default)
			)
			(layer "F.SilkS")
		)
		(fp_line
			(start 0.7874 0.4064)
			(end -0.7874 0.4064)
			(stroke
				(width 0.1524)
				(type default)
			)
			(layer "F.SilkS")
		)
		(fp_line
			(start -0.67945 -0.305054)
			(end -0.12065 -0.305054)
			(stroke
				(width 0.1)
				(type default)
			)
			(layer "F.Fab")
		)
		(fp_line
			(start -0.67945 0.3048)
			(end -0.67945 -0.305054)
			(stroke
				(width 0.1)
				(type default)
			)
			(layer "F.Fab")
		)
		(fp_line
			(start -0.12065 -0.305054)
			(end -0.12065 -0.2794)
			(stroke
				(width 0.1)
				(type default)
			)
			(layer "F.Fab")
		)
		(fp_line
			(start -0.12065 -0.2794)
			(end 0.12065 -0.2794)
			(stroke
				(width 0.1)
				(type default)
			)
			(layer "F.Fab")
		)
		(fp_line
			(start -0.12065 0.2794)
			(end -0.12065 0.3048)
			(stroke
				(width 0.1)
				(type default)
			)
			(layer "F.Fab")
		)
		(fp_line
			(start -0.12065 0.3048)
			(end -0.67945 0.3048)
			(stroke
				(width 0.1)
				(type default)
			)
			(layer "F.Fab")
		)
		(fp_line
			(start 0.120396 0.2794)
			(end -0.12065 0.2794)
			(stroke
				(width 0.1)
				(type default)
			)
			(layer "F.Fab")
		)
		(fp_line
			(start 0.120396 0.3048)
			(end 0.120396 0.2794)
			(stroke
				(width 0.1)
				(type default)
			)
			(layer "F.Fab")
		)
		(fp_line
			(start 0.12065 -0.3048)
			(end 0.67945 -0.3048)
			(stroke
				(width 0.1)
				(type default)
			)
			(layer "F.Fab")
		)
		(fp_line
			(start 0.12065 -0.2794)
			(end 0.12065 -0.3048)
			(stroke
				(width 0.1)
				(type default)
			)
			(layer "F.Fab")
		)
		(fp_line
			(start 0.67945 -0.3048)
			(end 0.67945 0.3048)
			(stroke
				(width 0.1)
				(type default)
			)
			(layer "F.Fab")
		)
		(fp_line
			(start 0.67945 0.3048)
			(end 0.120396 0.3048)
			(stroke
				(width 0.1)
				(type default)
			)
			(layer "F.Fab")
		)
		(pad "1" smd circle
			(at -0.40005 0)
			(size 0 0)
			(layers "F.Cu" "F.Mask" "F.Paste")
			(net "NIC2_BIF1_N")
		)
		(pad "2" smd circle
			(at 0.40005 0)
			(size 0 0)
			(layers "F.Cu" "F.Mask" "F.Paste")
			(net "GND")
		)
	)
)
